# T6G (Grand Teton) — schematic netlist excerpt (pin names and nets, part order shuffled) for the footprints in the layout excerpt that follows; sources: Cadence DE-HDL packaged netlist, KiCad conversion of 04192023_DAF0TMB3IC0_F0TG_MB_C_brd_V02_OCP.brd

J35  SCONN168_ME1016810202011  IO  pkg CON_F168S2H7D_P0-6W2-95_LUH  page 137
  GND_A1  = GND
  GND_A2  = GND
  GND_A3  = GND
  GND_A4  = GND
  GND_A5  = GND
  GND_A6  = GND
  SMCLK  = SMB_OCP_V3_2_3V3AUX_BUF_R_SCL
  SMDAT  = SMB_OCP_V3_2_3V3AUX_BUF_R_SDA
  \smrst#\  = RST_SMB_OCP_V3_2_N
  \prsnta#\  = OCP_V3_2_PRSNTA_R_N
  \perst1#\  = RST_PERST1_OCP_V3_2_N
  \prsntb2#\  = OCP_V3_2_PRSNT2_R_N
  GND_A13  = GND
  REFCLKN1  = CLK_100M_CPU1_CLK03_DN
  REFCLKP1  = CLK_100M_CPU1_CLK03_DP
  GND_A16  = GND
  PERN0  = P5E_CPU1_G1_RX_DN<0>
  PERP0  = P5E_CPU1_G1_RX_DP<0>
  GND_A19  = GND
  PERN1  = P5E_CPU1_G1_RX_DN<1>
  PERP1  = P5E_CPU1_G1_RX_DP<1>
  GND_A22  = GND
  PERN2  = P5E_CPU1_G1_RX_DN<2>
  PERP2  = P5E_CPU1_G1_RX_DP<2>
  GND_A25  = GND
  PERN3  = P5E_CPU1_G1_RX_DN<3>
  PERP3  = P5E_CPU1_G1_RX_DP<3>
  GND_A28  = GND
  GND_A29  = GND
  PERN4  = P5E_CPU1_G1_RX_DN<4>
  PERP4  = P5E_CPU1_G1_RX_DP<4>
  GND_A32  = GND
  PERN5  = P5E_CPU1_G1_RX_DN<5>
  PERP5  = P5E_CPU1_G1_RX_DP<5>
  GND_A35  = GND
  PERN6  = P5E_CPU1_G1_RX_DN<6>
  PERP6  = P5E_CPU1_G1_RX_DP<6>
  GND_A38  = GND
  PERN7  = P5E_CPU1_G1_RX_DN<7>
  PERP7  = P5E_CPU1_G1_RX_DP<7>
  GND_A41  = GND
  \prsntb1#\  = OCP_V3_2_PRSNT1_R_N
  GND_A43  = GND
  PERN8  = P5E_CPU1_G1_RX_DN<8>
  PERP8  = P5E_CPU1_G1_RX_DP<8>
  GND_A46  = GND
  PERN9  = P5E_CPU1_G1_RX_DN<9>
  PERP9  = P5E_CPU1_G1_RX_DP<9>
  GND_A49  = GND
  PERN10  = P5E_CPU1_G1_RX_DN<10>
  PERP10  = P5E_CPU1_G1_RX_DP<10>
  GND_A52  = GND
  PERN11  = P5E_CPU1_G1_RX_DN<11>
  PERP11  = P5E_CPU1_G1_RX_DP<11>
  GND_A55  = GND
  PERN12  = P5E_CPU1_G1_RX_DN<12>
  PERP12  = P5E_CPU1_G1_RX_DP<12>
  GND_A58  = GND
  PERN13  = P5E_CPU1_G1_RX_DN<13>
  PERP13  = P5E_CPU1_G1_RX_DP<13>
  GND_A61  = GND
  PERN14  = P5E_CPU1_G1_RX_DN<14>
  PERP14  = P5E_CPU1_G1_RX_DP<14>
  GND_A64  = GND
  PERN15  = P5E_CPU1_G1_RX_DN<15>
  PERP15  = P5E_CPU1_G1_RX_DP<15>
  GND_A67  = GND
  USB_DATN  = USB2_P10_DN
  USB_DATP  = USB2_P10_DP
  \pwrbrk0#\  = OCP_V3_2_PWRBRK_N
  \+12v_edge_b1\  = P12V_OCP_V3_2_R
  \+12v_edge_b2\  = P12V_OCP_V3_2_R
  \+12v_edge_b3\  = P12V_OCP_V3_2_R
  \+12v_edge_b4\  = P12V_OCP_V3_2_R
  \+12v_edge_b5\  = P12V_OCP_V3_2_R
  \+12v_edge_b6\  = P12V_OCP_V3_2_R
  \bif0#\  = OCP_V3_2_BIF0_R_N
  \bif1#\  = OCP_V3_2_BIF1_R_N
  \bif2#\  = OCP_V3_2_BIF2_R_N
  \perst0#\  = RST_PERST0_OCP_V3_2_N
  \+3.3v_edge\  = P3V3_OCP_V3_2
  AUX_PWR_EN  = OCP_V3_2_AUX_PWR_EN_R
  GND_B13  = GND
  REFCLKN0  = CLK_100M_CPU1_CLK02_DN
  REFCLKP0  = CLK_100M_CPU1_CLK02_DP
  GND_B16  = GND
  PETN0  = P5E_CPU1_G1_TX_C_DP<0>
  PETP0  = P5E_CPU1_G1_TX_C_DN<0>
  GND_B19  = GND
  PETN1  = P5E_CPU1_G1_TX_C_DP<1>
  PETP1  = P5E_CPU1_G1_TX_C_DN<1>
  GND_B22  = GND
  PETN2  = P5E_CPU1_G1_TX_C_DP<2>
  PETP2  = P5E_CPU1_G1_TX_C_DN<2>
  GND_B25  = GND
  PETN3  = P5E_CPU1_G1_TX_C_DP<3>
  PETP3  = P5E_CPU1_G1_TX_C_DN<3>
  GND_B28  = GND
  GND_B29  = GND
  PETN4  = P5E_CPU1_G1_TX_C_DP<4>
  PETP4  = P5E_CPU1_G1_TX_C_DN<4>
  GND_B32  = GND
  PETN5  = P5E_CPU1_G1_TX_C_DP<5>
  PETP5  = P5E_CPU1_G1_TX_C_DN<5>
  GND_B35  = GND
  PETN6  = P5E_CPU1_G1_TX_C_DP<6>
  PETP6  = P5E_CPU1_G1_TX_C_DN<6>
  GND_B38  = GND
  PETN7  = P5E_CPU1_G1_TX_C_DP<7>
  PETP7  = P5E_CPU1_G1_TX_C_DN<7>
  GND_B41  = GND
  \prsntb0#\  = OCP_V3_2_PRSNT0_R_N
  GND_B43  = GND
  PETN8  = P5E_CPU1_G1_TX_C_DP<8>
  PETP8  = P5E_CPU1_G1_TX_C_DN<8>
  GND_B46  = GND
  PETN9  = P5E_CPU1_G1_TX_C_DP<9>
  PETP9  = P5E_CPU1_G1_TX_C_DN<9>
  GND_B49  = GND
  PETN10  = P5E_CPU1_G1_TX_C_DP<10>
  PETP10  = P5E_CPU1_G1_TX_C_DN<10>
  GND_B52  = GND
  PETN11  = P5E_CPU1_G1_TX_C_DP<11>
  PETP11  = P5E_CPU1_G1_TX_C_DN<11>
  GND_B55  = GND
  PETN12  = P5E_CPU1_G1_TX_C_DP<12>
  PETP12  = P5E_CPU1_G1_TX_C_DN<12>
  GND_B58  = GND
  PETN13  = P5E_CPU1_G1_TX_C_DP<13>
  PETP13  = P5E_CPU1_G1_TX_C_DN<13>
  GND_B61  = GND
  PETN14  = P5E_CPU1_G1_TX_C_DP<14>
  PETP14  = P5E_CPU1_G1_TX_C_DN<14>
  GND_B64  = GND
  PETN15  = P5E_CPU1_G1_TX_C_DP<15>
  PETP15  = P5E_CPU1_G1_TX_C_DN<15>
  GND_B67  = GND
  RFU1_NC_B68  = TP_OCP_V3_2_B68
  RFU1_NC_B69  = TP_OCP_V3_2_B69
  \prsntb3#\  = OCP_V3_2_PRSNT3_R_N
  G1  = GND
  G2  = GND
  G3  = GND
  G4  = GND
  G5  = GND
  \perst2#\  = RST_PERST2_OCP_V3_2_N
  \perst3#\  = RST_PERST3_OCP_V3_2_N
  \wake#\  = IRQ_LVC3_OCP_V3_2_WAKE_N
  RBT_ARB_IN  = OCP_V3_2_ISO1_RBT_ARB_IN
  RBT_ARB_OUT  = OCP_V3_2_ISO2_RBT_ARB_OUT
  SLOT_ID1  = OCP_V3_2_ID1
  RBT_TX_EN  = NCSI_OCP_V3_2_TX_EN
  RBT_TXD1  = NCSI_OCP_V3_2_TXD1
  RBT_TXD0  = NCSI_OCP_V3_2_TXD0
  GND_OA10  = GND
  REFCLKN3  = CLK_100M_CPU1_CLK05_DN
  REFCLKP3  = CLK_100M_CPU1_CLK05_DP
  GND_OA13  = GND
  RBT_CLK_IN  = CLK_50M_NCSI_OCP_V3_2_ISO
  NIC_PWR_GOOD  = FM_OCP_V3_2_PWR_GOOD
  MAIN_PWR_EN  = OCP_V3_2_MAIN_PWR_EN_R
  \ld#\  = SGPIO_OCP_V3_2_LD_N
  DATA_IN  = SGPIO_OCP_V3_2_DATAIN
  DATA_OUT  = SGPIO_OCP_V3_2_DATAOUT
  CLK  = SGPIO_OCP_V3_2_CLK
  SLOT_ID0  = OCP_V3_2_ID0
  RBT_RXD1  = NCSI_OCP_V3_2_RXD1
  RBT_RXD0  = NCSI_OCP_V3_2_RXD0
  GND_OB10  = GND
  REFCLKN2  = CLK_100M_CPU1_CLK04_DN
  REFCLKP2  = CLK_100M_CPU1_CLK04_DP
  GND_OB13  = GND
  RBT_CRS_DV  = NCSI_OCP_V3_2_CRS_DV

(kicad_pcb
	(version 20260206)
	(generator "pcbnew")
	(generator_version "10.0")
	(general
		(thickness 1.6)
		(legacy_teardrops no)
	)
	(paper "A4")
	(title_block
		(title "04192023_DAF0TMB3IC0_F0TG_MB_C_brd_V02_OCP.brd")
		(comment 1 "Grand Teton / footprint 4922 of 8354 (J35), pads 134-175 of 175")
	)
	(layers
		(0 "F.Cu" signal "TOP")
		(4 "In1.Cu" signal "GND")
		(6 "In2.Cu" signal "IN1")
		(8 "In3.Cu" signal "GND1")
		(10 "In4.Cu" signal "IN2")
		(12 "In5.Cu" signal "GND2")
		(14 "In6.Cu" signal "IN3")
		(16 "In7.Cu" signal "GND3")
		(18 "In8.Cu" signal "VCC")
		(20 "In9.Cu" signal "VCC1")
		(22 "In10.Cu" signal "GND4")
		(24 "In11.Cu" signal "IN4")
		(26 "In12.Cu" signal "GND5")
		(28 "In13.Cu" signal "IN5")
		(30 "In14.Cu" signal "GND6")
		(32 "In15.Cu" signal "IN6")
		(34 "In16.Cu" signal "GND7")
		(2 "B.Cu" signal "BOTTOM")
		(9 "F.Adhes" user "F.Adhesive")
		(11 "B.Adhes" user "B.Adhesive")
		(13 "F.Paste" user "Package Geometry/Pastemask Top")
		(15 "B.Paste" user "Package Geometry/Pastemask Bottom")
		(5 "F.SilkS" user "Ref Des/Silkscreen Top")
		(7 "B.SilkS" user "Ref Des/Silkscreen Bottom")
		(1 "F.Mask" user "Board Geometry/Soldermask Top")
		(3 "B.Mask" user "Board Geometry/Soldermask Bottom")
		(17 "Dwgs.User" user "User.Drawings")
		(19 "Cmts.User" user "User.Comments")
		(21 "Eco1.User" user "User.Eco1")
		(23 "Eco2.User" user "User.Eco2")
		(25 "Edge.Cuts" user "Board Geometry/Outline")
		(27 "Margin" user)
		(31 "F.CrtYd" user "Package Geometry/Place Bound Top")
		(29 "B.CrtYd" user "Package Geometry/Place Bound Bottom")
		(35 "F.Fab" user "Ref Des/Assembly Top")
		(33 "B.Fab" user "Ref Des/Assembly Bottom")
	)
	(footprint ""
		(layer "F.Cu")
		(at 47.401988 -5.569966 -90)
		(property "Reference" "J35"
			(at -8.0772 -20.659598 0)
			(unlocked yes)
			(layer "F.SilkS")
			(effects
				(font
					(size 0.7874 0.5842)
					(thickness 0.1524)
				)
				(justify left)
			)
		)
		(property "Value" ""
			(at 0 0 270)
			(layer "F.Fab")
			(effects
				(font
					(size 1.27 1.27)
				)
			)
		)
		(duplicate_pad_numbers_are_jumpers no)
		(pad "B62" smd rect
			(at -5.700014 25.854914 180)
			(size 0.381 1.4478)
			(layers "F.Cu" "F.Mask" "F.Paste")
			(net "P5E_CPU1_G1_TX_C_DP<14>")
		)
		(pad "B63" smd rect
			(at -5.700014 26.455116 180)
			(size 0.381 1.4478)
			(layers "F.Cu" "F.Mask" "F.Paste")
			(net "P5E_CPU1_G1_TX_C_DN<14>")
		)
		(pad "B64" smd rect
			(at -5.700014 27.055064 180)
			(size 0.381 1.4478)
			(layers "F.Cu" "F.Mask" "F.Paste")
			(net "GND")
		)
		(pad "B65" smd rect
			(at -5.700014 27.655012 180)
			(size 0.381 1.4478)
			(layers "F.Cu" "F.Mask" "F.Paste")
			(net "P5E_CPU1_G1_TX_C_DP<15>")
		)
		(pad "B66" smd rect
			(at -5.700014 28.25496 180)
			(size 0.381 1.4478)
			(layers "F.Cu" "F.Mask" "F.Paste")
			(net "P5E_CPU1_G1_TX_C_DN<15>")
		)
		(pad "B67" smd rect
			(at -5.700014 28.854908 180)
			(size 0.381 1.4478)
			(layers "F.Cu" "F.Mask" "F.Paste")
			(net "GND")
		)
		(pad "B68" smd rect
			(at -5.700014 29.45511 180)
			(size 0.381 1.4478)
			(layers "F.Cu" "F.Mask" "F.Paste")
			(net "TP_OCP_V3_2_B68")
		)
		(pad "B69" smd rect
			(at -5.700014 30.055058 180)
			(size 0.381 1.4478)
			(layers "F.Cu" "F.Mask" "F.Paste")
			(net "TP_OCP_V3_2_B69")
		)
		(pad "B70" smd rect
			(at -5.700014 30.655006 180)
			(size 0.381 1.4478)
			(layers "F.Cu" "F.Mask" "F.Paste")
			(net "OCP_V3_2_PRSNT3_R_N")
		)
		(pad "G1" thru_hole circle
			(at 2.400046 -32.759904 180)
			(size 1.6256 1.6256)
			(drill 1.1176)
			(layers "*.Cu" "*.Mask")
			(remove_unused_layers no)
			(net "GND")
			(clearance 0)
		)
		(pad "G2" thru_hole circle
			(at 2.400046 -20.379944 180)
			(size 1.6256 1.6256)
			(drill 1.1176)
			(layers "*.Cu" "*.Mask")
			(remove_unused_layers no)
			(net "GND")
			(clearance 0)
		)
		(pad "G3" thru_hole circle
			(at 2.400046 0 180)
			(size 1.6256 1.6256)
			(drill 1.1176)
			(layers "*.Cu" "*.Mask")
			(remove_unused_layers no)
			(net "GND")
			(clearance 0)
		)
		(pad "G4" thru_hole circle
			(at 2.400046 12.5349 180)
			(size 1.6256 1.6256)
			(drill 1.1176)
			(layers "*.Cu" "*.Mask")
			(remove_unused_layers no)
			(net "GND")
			(clearance 0)
		)
		(pad "G5" thru_hole circle
			(at 2.400046 32.759904 180)
			(size 1.6256 1.6256)
			(drill 1.1176)
			(layers "*.Cu" "*.Mask")
			(remove_unused_layers no)
			(net "GND")
			(clearance 0)
		)
		(pad "OA1" smd rect
			(at -2.750058 -30.660086 180)
			(size 0.381 1.4478)
			(layers "F.Cu" "F.Mask" "F.Paste")
			(net "RST_PERST2_OCP_V3_2_N")
		)
		(pad "OA2" smd rect
			(at -2.750058 -30.059884 180)
			(size 0.381 1.4478)
			(layers "F.Cu" "F.Mask" "F.Paste")
			(net "RST_PERST3_OCP_V3_2_N")
		)
		(pad "OA3" smd rect
			(at -2.750058 -29.459936 180)
			(size 0.381 1.4478)
			(layers "F.Cu" "F.Mask" "F.Paste")
			(net "IRQ_LVC3_OCP_V3_2_WAKE_N")
		)
		(pad "OA4" smd rect
			(at -2.750058 -28.859988 180)
			(size 0.381 1.4478)
			(layers "F.Cu" "F.Mask" "F.Paste")
			(net "OCP_V3_2_ISO1_RBT_ARB_IN")
		)
		(pad "OA5" smd rect
			(at -2.750058 -28.26004 180)
			(size 0.381 1.4478)
			(layers "F.Cu" "F.Mask" "F.Paste")
			(net "OCP_V3_2_ISO2_RBT_ARB_OUT")
		)
		(pad "OA6" smd rect
			(at -2.750058 -27.660092 180)
			(size 0.381 1.4478)
			(layers "F.Cu" "F.Mask" "F.Paste")
			(net "OCP_V3_2_ID1")
		)
		(pad "OA7" smd rect
			(at -2.750058 -27.05989 180)
			(size 0.381 1.4478)
			(layers "F.Cu" "F.Mask" "F.Paste")
			(net "NCSI_OCP_V3_2_TX_EN")
		)
		(pad "OA8" smd rect
			(at -2.750058 -26.459942 180)
			(size 0.381 1.4478)
			(layers "F.Cu" "F.Mask" "F.Paste")
			(net "NCSI_OCP_V3_2_TXD1")
		)
		(pad "OA9" smd rect
			(at -2.750058 -25.859994 180)
			(size 0.381 1.4478)
			(layers "F.Cu" "F.Mask" "F.Paste")
			(net "NCSI_OCP_V3_2_TXD0")
		)
		(pad "OA10" smd rect
			(at -2.750058 -25.260046 180)
			(size 0.381 1.4478)
			(layers "F.Cu" "F.Mask" "F.Paste")
			(net "GND")
		)
		(pad "OA11" smd rect
			(at -2.750058 -24.660098 180)
			(size 0.381 1.4478)
			(layers "F.Cu" "F.Mask" "F.Paste")
			(net "CLK_100M_CPU1_CLK05_DN")
		)
		(pad "OA12" smd rect
			(at -2.750058 -24.059896 180)
			(size 0.381 1.4478)
			(layers "F.Cu" "F.Mask" "F.Paste")
			(net "CLK_100M_CPU1_CLK05_DP")
		)
		(pad "OA13" smd rect
			(at -2.750058 -23.459948 180)
			(size 0.381 1.4478)
			(layers "F.Cu" "F.Mask" "F.Paste")
			(net "GND")
		)
		(pad "OA14" smd rect
			(at -2.750058 -22.86 180)
			(size 0.381 1.4478)
			(layers "F.Cu" "F.Mask" "F.Paste")
			(net "CLK_50M_NCSI_OCP_V3_2_ISO")
		)
		(pad "OB1" smd rect
			(at -5.700014 -30.660086 180)
			(size 0.381 1.4478)
			(layers "F.Cu" "F.Mask" "F.Paste")
			(net "FM_OCP_V3_2_PWR_GOOD")
		)
		(pad "OB2" smd rect
			(at -5.700014 -30.059884 180)
			(size 0.381 1.4478)
			(layers "F.Cu" "F.Mask" "F.Paste")
			(net "OCP_V3_2_MAIN_PWR_EN_R")
		)
		(pad "OB3" smd rect
			(at -5.700014 -29.459936 180)
			(size 0.381 1.4478)
			(layers "F.Cu" "F.Mask" "F.Paste")
			(net "SGPIO_OCP_V3_2_LD_N")
		)
		(pad "OB4" smd rect
			(at -5.700014 -28.859988 180)
			(size 0.381 1.4478)
			(layers "F.Cu" "F.Mask" "F.Paste")
			(net "SGPIO_OCP_V3_2_DATAIN")
		)
		(pad "OB5" smd rect
			(at -5.700014 -28.26004 180)
			(size 0.381 1.4478)
			(layers "F.Cu" "F.Mask" "F.Paste")
			(net "SGPIO_OCP_V3_2_DATAOUT")
		)
		(pad "OB6" smd rect
			(at -5.700014 -27.660092 180)
			(size 0.381 1.4478)
			(layers "F.Cu" "F.Mask" "F.Paste")
			(net "SGPIO_OCP_V3_2_CLK")
		)
		(pad "OB7" smd rect
			(at -5.700014 -27.05989 180)
			(size 0.381 1.4478)
			(layers "F.Cu" "F.Mask" "F.Paste")
			(net "OCP_V3_2_ID0")
		)
		(pad "OB8" smd rect
			(at -5.700014 -26.459942 180)
			(size 0.381 1.4478)
			(layers "F.Cu" "F.Mask" "F.Paste")
			(net "NCSI_OCP_V3_2_RXD1")
		)
		(pad "OB9" smd rect
			(at -5.700014 -25.859994 180)
			(size 0.381 1.4478)
			(layers "F.Cu" "F.Mask" "F.Paste")
			(net "NCSI_OCP_V3_2_RXD0")
		)
		(pad "OB10" smd rect
			(at -5.700014 -25.260046 180)
			(size 0.381 1.4478)
			(layers "F.Cu" "F.Mask" "F.Paste")
			(net "GND")
		)
		(pad "OB11" smd rect
			(at -5.700014 -24.660098 180)
			(size 0.381 1.4478)
			(layers "F.Cu" "F.Mask" "F.Paste")
			(net "CLK_100M_CPU1_CLK04_DN")
		)
		(pad "OB12" smd rect
			(at -5.700014 -24.059896 180)
			(size 0.381 1.4478)
			(layers "F.Cu" "F.Mask" "F.Paste")
			(net "CLK_100M_CPU1_CLK04_DP")
		)
		(pad "OB13" smd rect
			(at -5.700014 -23.459948 180)
			(size 0.381 1.4478)
			(layers "F.Cu" "F.Mask" "F.Paste")
			(net "GND")
		)
		(pad "OB14" smd rect
			(at -5.700014 -22.86 180)
			(size 0.381 1.4478)
			(layers "F.Cu" "F.Mask" "F.Paste")
			(net "NCSI_OCP_V3_2_CRS_DV")
		)
	)
)
